(kicad_pcb
	(version 20260206)
	(generator "pcbnew")
	(generator_version "10.0")
	(general
		(thickness 1.6)
		(legacy_teardrops no)
	)
	(paper "A4")
	(title_block
		(title "03242023_DA0F0TMBIJ0_F0T_Motherboard_J_brd_V01_OCP.brd")
		(comment 1 "Grand Teton / footprint 1660 of 6105 (J24), pads 225-291 of 291")
	)
	(layers
		(0 "F.Cu" signal "TOP")
		(4 "In1.Cu" signal "GND")
		(6 "In2.Cu" signal "IN1")
		(8 "In3.Cu" signal "GND1")
		(10 "In4.Cu" signal "IN2")
		(12 "In5.Cu" signal "GND2")
		(14 "In6.Cu" signal "IN3")
		(16 "In7.Cu" signal "GND3")
		(18 "In8.Cu" signal "VCC")
		(20 "In9.Cu" signal "VCC1")
		(22 "In10.Cu" signal "GND4")
		(24 "In11.Cu" signal "IN4")
		(26 "In12.Cu" signal "GND5")
		(28 "In13.Cu" signal "IN5")
		(30 "In14.Cu" signal "GND6")
		(32 "In15.Cu" signal "IN6")
		(34 "In16.Cu" signal "GND7")
		(2 "B.Cu" signal "BOTTOM")
		(9 "F.Adhes" user "F.Adhesive")
		(11 "B.Adhes" user "B.Adhesive")
		(13 "F.Paste" user "Package Geometry/Pastemask Top")
		(15 "B.Paste" user "Package Geometry/Pastemask Bottom")
		(5 "F.SilkS" user "Ref Des/Silkscreen Top")
		(7 "B.SilkS" user "Ref Des/Silkscreen Bottom")
		(1 "F.Mask" user "Board Geometry/Soldermask Top")
		(3 "B.Mask" user "Board Geometry/Soldermask Bottom")
		(17 "Dwgs.User" user "User.Drawings")
		(19 "Cmts.User" user "User.Comments")
		(21 "Eco1.User" user "User.Eco1")
		(23 "Eco2.User" user "User.Eco2")
		(25 "Edge.Cuts" user "Board Geometry/Outline")
		(27 "Margin" user)
		(31 "F.CrtYd" user "Package Geometry/Place Bound Top")
		(29 "B.CrtYd" user "Package Geometry/Place Bound Bottom")
		(35 "F.Fab" user "Ref Des/Assembly Top")
		(33 "B.Fab" user "Ref Des/Assembly Bottom")
	)
	(footprint ""
		(layer "F.Cu")
		(at 17.73428 -258.091686)
		(property "Reference" "J24"
			(at -3.0607 -81.901792 0)
			(unlocked yes)
			(layer "F.SilkS")
			(effects
				(font
					(size 0.7874 0.5842)
					(thickness 0.1524)
				)
				(justify left)
			)
		)
		(property "Value" ""
			(at 0 0 0)
			(layer "F.Fab")
			(effects
				(font
					(size 1.27 1.27)
				)
			)
		)
		(duplicate_pad_numbers_are_jumpers no)
		(pad "225" smd rect
			(at 2.050034 9.774936 270)
			(size 0.519938 1.4986)
			(layers "F.Cu" "F.Mask" "F.Paste")
			(net "M_D_CPU1_SB_CA<5>")
		)
		(pad "226" smd rect
			(at 2.050034 10.625074 270)
			(size 0.519938 1.4986)
			(layers "F.Cu" "F.Mask" "F.Paste")
			(net "GND")
		)
		(pad "227" smd rect
			(at 2.050034 11.474958 270)
			(size 0.519938 1.4986)
			(layers "F.Cu" "F.Mask" "F.Paste")
			(net "M_D_CPU1_SB_PAR")
		)
		(pad "228" smd rect
			(at 2.050034 12.325096 270)
			(size 0.519938 1.4986)
			(layers "F.Cu" "F.Mask" "F.Paste")
			(net "GND")
		)
		(pad "229" smd rect
			(at 2.050034 13.17498 270)
			(size 0.519938 1.4986)
			(layers "F.Cu" "F.Mask" "F.Paste")
			(net "M_D_CPU1_SB_CS_N<3>")
		)
		(pad "230" smd rect
			(at 2.050034 14.025118 270)
			(size 0.519938 1.4986)
			(layers "F.Cu" "F.Mask" "F.Paste")
			(net "GND")
		)
		(pad "231" smd rect
			(at 2.050034 14.875002 270)
			(size 0.519938 1.4986)
			(layers "F.Cu" "F.Mask" "F.Paste")
			(net "TP_CHD_CPU1_DIMM2_FRU_5")
		)
		(pad "232" smd rect
			(at 2.050034 15.724886 270)
			(size 0.519938 1.4986)
			(layers "F.Cu" "F.Mask" "F.Paste")
			(net "TP_CHD_CPU1_DIMM2_FRU_6")
		)
		(pad "233" smd rect
			(at 2.050034 16.575024 270)
			(size 0.519938 1.4986)
			(layers "F.Cu" "F.Mask" "F.Paste")
			(net "GND")
		)
		(pad "234" smd rect
			(at 2.050034 17.424908 270)
			(size 0.519938 1.4986)
			(layers "F.Cu" "F.Mask" "F.Paste")
			(net "M_D_CPU1_SB_CB<6>")
		)
		(pad "235" smd rect
			(at 2.050034 18.275046 270)
			(size 0.519938 1.4986)
			(layers "F.Cu" "F.Mask" "F.Paste")
			(net "GND")
		)
		(pad "236" smd rect
			(at 2.050034 19.12493 270)
			(size 0.519938 1.4986)
			(layers "F.Cu" "F.Mask" "F.Paste")
			(net "M_D_CPU1_SB_CB<7>")
		)
		(pad "237" smd rect
			(at 2.050034 19.975068 270)
			(size 0.519938 1.4986)
			(layers "F.Cu" "F.Mask" "F.Paste")
			(net "GND")
		)
		(pad "238" smd rect
			(at 2.050034 20.824952 270)
			(size 0.519938 1.4986)
			(layers "F.Cu" "F.Mask" "F.Paste")
			(net "M_D_CPU1_SB_DQS_DN<4>")
		)
		(pad "239" smd rect
			(at 2.050034 21.67509 270)
			(size 0.519938 1.4986)
			(layers "F.Cu" "F.Mask" "F.Paste")
			(net "M_D_CPU1_SB_DQS_DP<4>")
		)
		(pad "240" smd rect
			(at 2.050034 22.524974 270)
			(size 0.519938 1.4986)
			(layers "F.Cu" "F.Mask" "F.Paste")
			(net "GND")
		)
		(pad "241" smd rect
			(at 2.050034 23.375112 270)
			(size 0.519938 1.4986)
			(layers "F.Cu" "F.Mask" "F.Paste")
			(net "M_D_CPU1_SB_CB<2>")
		)
		(pad "242" smd rect
			(at 2.050034 24.224996 270)
			(size 0.519938 1.4986)
			(layers "F.Cu" "F.Mask" "F.Paste")
			(net "GND")
		)
		(pad "243" smd rect
			(at 2.050034 25.07488 270)
			(size 0.519938 1.4986)
			(layers "F.Cu" "F.Mask" "F.Paste")
			(net "M_D_CPU1_SB_CB<3>")
		)
		(pad "244" smd rect
			(at 2.050034 25.925018 270)
			(size 0.519938 1.4986)
			(layers "F.Cu" "F.Mask" "F.Paste")
			(net "GND")
		)
		(pad "245" smd rect
			(at 2.050034 26.774902 270)
			(size 0.519938 1.4986)
			(layers "F.Cu" "F.Mask" "F.Paste")
			(net "M_D_CPU1_SB_DQ<2>")
		)
		(pad "246" smd rect
			(at 2.050034 27.62504 270)
			(size 0.519938 1.4986)
			(layers "F.Cu" "F.Mask" "F.Paste")
			(net "GND")
		)
		(pad "247" smd rect
			(at 2.050034 28.474924 270)
			(size 0.519938 1.4986)
			(layers "F.Cu" "F.Mask" "F.Paste")
			(net "M_D_CPU1_SB_DQ<3>")
		)
		(pad "248" smd rect
			(at 2.050034 29.325062 270)
			(size 0.519938 1.4986)
			(layers "F.Cu" "F.Mask" "F.Paste")
			(net "GND")
		)
		(pad "249" smd rect
			(at 2.050034 30.174946 270)
			(size 0.519938 1.4986)
			(layers "F.Cu" "F.Mask" "F.Paste")
			(net "M_D_CPU1_SB_DQS_DN<5>")
		)
		(pad "250" smd rect
			(at 2.050034 31.025084 270)
			(size 0.519938 1.4986)
			(layers "F.Cu" "F.Mask" "F.Paste")
			(net "M_D_CPU1_SB_DQS_DP<5>")
		)
		(pad "251" smd rect
			(at 2.050034 31.874968 270)
			(size 0.519938 1.4986)
			(layers "F.Cu" "F.Mask" "F.Paste")
			(net "GND")
		)
		(pad "252" smd rect
			(at 2.050034 32.725106 270)
			(size 0.519938 1.4986)
			(layers "F.Cu" "F.Mask" "F.Paste")
			(net "M_D_CPU1_SB_DQ<6>")
		)
		(pad "253" smd rect
			(at 2.050034 33.57499 270)
			(size 0.519938 1.4986)
			(layers "F.Cu" "F.Mask" "F.Paste")
			(net "GND")
		)
		(pad "254" smd rect
			(at 2.050034 34.425128 270)
			(size 0.519938 1.4986)
			(layers "F.Cu" "F.Mask" "F.Paste")
			(net "M_D_CPU1_SB_DQ<7>")
		)
		(pad "255" smd rect
			(at 2.050034 35.275012 270)
			(size 0.519938 1.4986)
			(layers "F.Cu" "F.Mask" "F.Paste")
			(net "GND")
		)
		(pad "256" smd rect
			(at 2.050034 36.124896 270)
			(size 0.519938 1.4986)
			(layers "F.Cu" "F.Mask" "F.Paste")
			(net "M_D_CPU1_SB_DQ<10>")
		)
		(pad "257" smd rect
			(at 2.050034 36.975034 270)
			(size 0.519938 1.4986)
			(layers "F.Cu" "F.Mask" "F.Paste")
			(net "GND")
		)
		(pad "258" smd rect
			(at 2.050034 37.824918 270)
			(size 0.519938 1.4986)
			(layers "F.Cu" "F.Mask" "F.Paste")
			(net "M_D_CPU1_SB_DQ<11>")
		)
		(pad "259" smd rect
			(at 2.050034 38.675056 270)
			(size 0.519938 1.4986)
			(layers "F.Cu" "F.Mask" "F.Paste")
			(net "GND")
		)
		(pad "260" smd rect
			(at 2.050034 39.52494 270)
			(size 0.519938 1.4986)
			(layers "F.Cu" "F.Mask" "F.Paste")
			(net "M_D_CPU1_SB_DQS_DN<6>")
		)
		(pad "261" smd rect
			(at 2.050034 40.375078 270)
			(size 0.519938 1.4986)
			(layers "F.Cu" "F.Mask" "F.Paste")
			(net "M_D_CPU1_SB_DQS_DP<6>")
		)
		(pad "262" smd rect
			(at 2.050034 41.224962 270)
			(size 0.519938 1.4986)
			(layers "F.Cu" "F.Mask" "F.Paste")
			(net "GND")
		)
		(pad "263" smd rect
			(at 2.050034 42.0751 270)
			(size 0.519938 1.4986)
			(layers "F.Cu" "F.Mask" "F.Paste")
			(net "M_D_CPU1_SB_DQ<14>")
		)
		(pad "264" smd rect
			(at 2.050034 42.924984 270)
			(size 0.519938 1.4986)
			(layers "F.Cu" "F.Mask" "F.Paste")
			(net "GND")
		)
		(pad "265" smd rect
			(at 2.050034 43.775122 270)
			(size 0.519938 1.4986)
			(layers "F.Cu" "F.Mask" "F.Paste")
			(net "M_D_CPU1_SB_DQ<15>")
		)
		(pad "266" smd rect
			(at 2.050034 44.625006 270)
			(size 0.519938 1.4986)
			(layers "F.Cu" "F.Mask" "F.Paste")
			(net "GND")
		)
		(pad "267" smd rect
			(at 2.050034 45.47489 270)
			(size 0.519938 1.4986)
			(layers "F.Cu" "F.Mask" "F.Paste")
			(net "M_D_CPU1_SB_DQ<18>")
		)
		(pad "268" smd rect
			(at 2.050034 46.325028 270)
			(size 0.519938 1.4986)
			(layers "F.Cu" "F.Mask" "F.Paste")
			(net "GND")
		)
		(pad "269" smd rect
			(at 2.050034 47.174912 270)
			(size 0.519938 1.4986)
			(layers "F.Cu" "F.Mask" "F.Paste")
			(net "M_D_CPU1_SB_DQ<19>")
		)
		(pad "270" smd rect
			(at 2.050034 48.02505 270)
			(size 0.519938 1.4986)
			(layers "F.Cu" "F.Mask" "F.Paste")
			(net "GND")
		)
		(pad "271" smd rect
			(at 2.050034 48.874934 270)
			(size 0.519938 1.4986)
			(layers "F.Cu" "F.Mask" "F.Paste")
			(net "M_D_CPU1_SB_DQS_DN<7>")
		)
		(pad "272" smd rect
			(at 2.050034 49.725072 270)
			(size 0.519938 1.4986)
			(layers "F.Cu" "F.Mask" "F.Paste")
			(net "M_D_CPU1_SB_DQS_DP<7>")
		)
		(pad "273" smd rect
			(at 2.050034 50.574956 270)
			(size 0.519938 1.4986)
			(layers "F.Cu" "F.Mask" "F.Paste")
			(net "GND")
		)
		(pad "274" smd rect
			(at 2.050034 51.425094 270)
			(size 0.519938 1.4986)
			(layers "F.Cu" "F.Mask" "F.Paste")
			(net "M_D_CPU1_SB_DQ<22>")
		)
		(pad "275" smd rect
			(at 2.050034 52.274978 270)
			(size 0.519938 1.4986)
			(layers "F.Cu" "F.Mask" "F.Paste")
			(net "GND")
		)
		(pad "276" smd rect
			(at 2.050034 53.125116 270)
			(size 0.519938 1.4986)
			(layers "F.Cu" "F.Mask" "F.Paste")
			(net "M_D_CPU1_SB_DQ<23>")
		)
		(pad "277" smd rect
			(at 2.050034 53.975 270)
			(size 0.519938 1.4986)
			(layers "F.Cu" "F.Mask" "F.Paste")
			(net "GND")
		)
		(pad "278" smd rect
			(at 2.050034 54.824884 270)
			(size 0.519938 1.4986)
			(layers "F.Cu" "F.Mask" "F.Paste")
			(net "M_D_CPU1_SB_DQ<26>")
		)
		(pad "279" smd rect
			(at 2.050034 55.675022 270)
			(size 0.519938 1.4986)
			(layers "F.Cu" "F.Mask" "F.Paste")
			(net "GND")
		)
		(pad "280" smd rect
			(at 2.050034 56.524906 270)
			(size 0.519938 1.4986)
			(layers "F.Cu" "F.Mask" "F.Paste")
			(net "M_D_CPU1_SB_DQ<27>")
		)
		(pad "281" smd rect
			(at 2.050034 57.375044 270)
			(size 0.519938 1.4986)
			(layers "F.Cu" "F.Mask" "F.Paste")
			(net "GND")
		)
		(pad "282" smd rect
			(at 2.050034 58.224928 270)
			(size 0.519938 1.4986)
			(layers "F.Cu" "F.Mask" "F.Paste")
			(net "M_D_CPU1_SB_DQS_DN<8>")
		)
		(pad "283" smd rect
			(at 2.050034 59.075066 270)
			(size 0.519938 1.4986)
			(layers "F.Cu" "F.Mask" "F.Paste")
			(net "M_D_CPU1_SB_DQS_DP<8>")
		)
		(pad "284" smd rect
			(at 2.050034 59.92495 270)
			(size 0.519938 1.4986)
			(layers "F.Cu" "F.Mask" "F.Paste")
			(net "GND")
		)
		(pad "285" smd rect
			(at 2.050034 60.775088 270)
			(size 0.519938 1.4986)
			(layers "F.Cu" "F.Mask" "F.Paste")
			(net "M_D_CPU1_SB_DQ<30>")
		)
		(pad "286" smd rect
			(at 2.050034 61.624972 270)
			(size 0.519938 1.4986)
			(layers "F.Cu" "F.Mask" "F.Paste")
			(net "GND")
		)
		(pad "287" smd rect
			(at 2.050034 62.47511 270)
			(size 0.519938 1.4986)
			(layers "F.Cu" "F.Mask" "F.Paste")
			(net "M_D_CPU1_SB_DQ<31>")
		)
		(pad "288" smd rect
			(at 2.050034 63.324994 270)
			(size 0.519938 1.4986)
			(layers "F.Cu" "F.Mask" "F.Paste")
			(net "GND")
		)
		(pad "G1" thru_hole oval
			(at 0 -68.97497)
			(size 2.8194 1.5748)
			(drill oval 2.4384 1.1938)
			(layers "*.Cu" "*.Mask")
			(remove_unused_layers no)
			(net "GND")
			(clearance 0.127)
			(thermal_gap 0.127)
		)
		(pad "G2" thru_hole oval
			(at 0 3.875024)
			(size 2.8194 1.5748)
			(drill oval 2.4384 1.1938)
			(layers "*.Cu" "*.Mask")
			(remove_unused_layers no)
			(net "GND")
			(clearance 0.127)
			(thermal_gap 0.127)
		)
		(pad "G3" thru_hole oval
			(at 0 68.97497)
			(size 2.8194 1.5748)
			(drill oval 2.4384 1.1938)
			(layers "*.Cu" "*.Mask")
			(remove_unused_layers no)
			(net "GND")
			(clearance 0.127)
			(thermal_gap 0.127)
		)
	)
)
